# S9S_MB_2U (Grand Teton) — schematic netlist excerpt (pin names and nets, part order shuffled) for the footprints in the layout excerpt that follows; sources: Cadence DE-HDL packaged netlist, KiCad conversion of 03242023_DA0F0TMBIJ0_F0T_Motherboard_J_brd_V01_OCP.brd

U15  QS3VH257QG8  IC  pkg SMLF  page 229
  S  = FM_SPD_REMOTE_EN
  I0A  = I3C_SPD_DDRABCD_CPU0_R_SCL
  I1A  = I3C_SPD_DDRABCD_CPU0_BMC_SCL
  YA  = I3C_SPD_DDRABCD_CPU0_LVC1_R_SCL
  I0B  = I3C_SPD_DDRABCD_CPU0_R_SDA
  I1B  = I3C_SPD_DDRABCD_CPU0_BMC_SDA
  YB  = I3C_SPD_DDRABCD_CPU0_LVC1_R_SDA
  GND  = GND
  YC  = I3C_SPD_DDREFGH_CPU0_LVC1_R_SCL
  I1C  = I3C_SPD_DDREFGH_CPU0_BMC_SCL
  I0C  = I3C_SPD_DDREFGH_CPU0_R_SCL
  YD  = I3C_SPD_DDREFGH_CPU0_LVC1_R_SDA
  I1D  = I3C_SPD_DDREFGH_CPU0_BMC_SDA
  I0D  = I3C_SPD_DDREFGH_CPU0_R_SDA
  \e*\  = PD_I3C_SPD_DDR_CPU0_OE_N
  VCC  = P3V3_AUX

(kicad_pcb
	(version 20260206)
	(generator "pcbnew")
	(generator_version "10.0")
	(general
		(thickness 1.6)
		(legacy_teardrops no)
	)
	(paper "A4")
	(title_block
		(title "03242023_DA0F0TMBIJ0_F0T_Motherboard_J_brd_V01_OCP.brd")
		(comment 1 "Grand Teton / footprints 4924-4924 of 6105")
	)
	(layers
		(0 "F.Cu" signal "TOP")
		(4 "In1.Cu" signal "GND")
		(6 "In2.Cu" signal "IN1")
		(8 "In3.Cu" signal "GND1")
		(10 "In4.Cu" signal "IN2")
		(12 "In5.Cu" signal "GND2")
		(14 "In6.Cu" signal "IN3")
		(16 "In7.Cu" signal "GND3")
		(18 "In8.Cu" signal "VCC")
		(20 "In9.Cu" signal "VCC1")
		(22 "In10.Cu" signal "GND4")
		(24 "In11.Cu" signal "IN4")
		(26 "In12.Cu" signal "GND5")
		(28 "In13.Cu" signal "IN5")
		(30 "In14.Cu" signal "GND6")
		(32 "In15.Cu" signal "IN6")
		(34 "In16.Cu" signal "GND7")
		(2 "B.Cu" signal "BOTTOM")
		(9 "F.Adhes" user "F.Adhesive")
		(11 "B.Adhes" user "B.Adhesive")
		(13 "F.Paste" user "Package Geometry/Pastemask Top")
		(15 "B.Paste" user "Package Geometry/Pastemask Bottom")
		(5 "F.SilkS" user "Ref Des/Silkscreen Top")
		(7 "B.SilkS" user "Ref Des/Silkscreen Bottom")
		(1 "F.Mask" user "Board Geometry/Soldermask Top")
		(3 "B.Mask" user "Board Geometry/Soldermask Bottom")
		(17 "Dwgs.User" user "User.Drawings")
		(19 "Cmts.User" user "User.Comments")
		(21 "Eco1.User" user "User.Eco1")
		(23 "Eco2.User" user "User.Eco2")
		(25 "Edge.Cuts" user "Board Geometry/Outline")
		(27 "Margin" user)
		(31 "F.CrtYd" user "Package Geometry/Place Bound Top")
		(29 "B.CrtYd" user "Package Geometry/Place Bound Bottom")
		(35 "F.Fab" user "Ref Des/Assembly Top")
		(33 "B.Fab" user "Ref Des/Assembly Bottom")
	)
	(footprint ""
		(layer "B.Cu")
		(at 298.566332 -152.038558 180)
		(property "Reference" "U15"
			(at -1.392936 -4.58851 0)
			(unlocked yes)
			(layer "B.SilkS")
			(effects
				(font
					(size 0.7874 0.5842)
					(thickness 0.1524)
				)
				(justify left mirror)
			)
		)
		(property "Value" ""
			(at 0 0 0)
			(layer "B.Fab")
			(effects
				(font
					(size 1.27 1.27)
				)
				(justify mirror)
			)
		)
		(duplicate_pad_numbers_are_jumpers no)
		(fp_line
			(start 1.7272 2.489962)
			(end 1.7272 -2.489962)
			(stroke
				(width 0.1524)
				(type default)
			)
			(layer "B.SilkS")
		)
		(fp_line
			(start 1.7272 -2.489962)
			(end 0.779018 -2.489962)
			(stroke
				(width 0.1524)
				(type default)
			)
			(layer "B.SilkS")
		)
		(fp_line
			(start 0.779018 -2.489962)
			(end 0 -1.710944)
			(stroke
				(width 0.1524)
				(type default)
			)
			(layer "B.SilkS")
		)
		(fp_line
			(start 0 -1.710944)
			(end -0.779018 -2.489962)
			(stroke
				(width 0.1524)
				(type default)
			)
			(layer "B.SilkS")
		)
		(fp_line
			(start -0.779018 -2.489962)
			(end -1.7272 -2.489962)
			(stroke
				(width 0.1524)
				(type default)
			)
			(layer "B.SilkS")
		)
		(fp_line
			(start -1.7272 2.489962)
			(end 1.7272 2.489962)
			(stroke
				(width 0.1524)
				(type default)
			)
			(layer "B.SilkS")
		)
		(fp_line
			(start -1.7272 -2.489962)
			(end -1.7272 2.489962)
			(stroke
				(width 0.1524)
				(type default)
			)
			(layer "B.SilkS")
		)
		(fp_poly
			(pts
				(xy 3.307842 -3.782314) (xy 2.799842 -2.766314) (xy 2.291842 -3.782314)
			)
			(stroke
				(width 0)
				(type default)
			)
			(fill yes)
			(layer "B.SilkS")
		)
		(fp_line
			(start 1.994916 2.489962)
			(end 1.994916 -2.489962)
			(stroke
				(width 0.1)
				(type default)
			)
			(layer "B.Fab")
		)
		(fp_line
			(start 1.994916 -2.489962)
			(end -1.994916 -2.489962)
			(stroke
				(width 0.1)
				(type default)
			)
			(layer "B.Fab")
		)
		(fp_line
			(start -1.994916 2.489962)
			(end 1.994916 2.489962)
			(stroke
				(width 0.1)
				(type default)
			)
			(layer "B.Fab")
		)
		(fp_line
			(start -1.994916 -2.489962)
			(end -1.994916 2.489962)
			(stroke
				(width 0.1)
				(type default)
			)
			(layer "B.Fab")
		)
		(fp_poly
			(pts
				(xy 4.837176 -2.7305) (xy 4.837176 -1.7145) (xy 3.821176 -2.2225)
			)
			(stroke
				(width 0)
				(type default)
			)
			(fill yes)
			(layer "B.Fab")
		)
		(pad "1" smd rect
			(at 2.6924 -2.2225 90)
			(size 0.4318 1.6764)
			(layers "B.Cu" "B.Mask" "B.Paste")
			(net "FM_SPD_REMOTE_EN")
		)
		(pad "2" smd rect
			(at 2.6924 -1.5875 90)
			(size 0.4318 1.6764)
			(layers "B.Cu" "B.Mask" "B.Paste")
			(net "I3C_SPD_DDRABCD_CPU0_R_SCL")
		)
		(pad "3" smd rect
			(at 2.6924 -0.9525 90)
			(size 0.4318 1.6764)
			(layers "B.Cu" "B.Mask" "B.Paste")
			(net "I3C_SPD_DDRABCD_CPU0_BMC_SCL")
		)
		(pad "4" smd rect
			(at 2.6924 -0.3175 90)
			(size 0.4318 1.6764)
			(layers "B.Cu" "B.Mask" "B.Paste")
			(net "I3C_SPD_DDRABCD_CPU0_LVC1_R_SCL")
		)
		(pad "5" smd rect
			(at 2.6924 0.3175 90)
			(size 0.4318 1.6764)
			(layers "B.Cu" "B.Mask" "B.Paste")
			(net "I3C_SPD_DDRABCD_CPU0_R_SDA")
		)
		(pad "6" smd rect
			(at 2.6924 0.9525 90)
			(size 0.4318 1.6764)
			(layers "B.Cu" "B.Mask" "B.Paste")
			(net "I3C_SPD_DDRABCD_CPU0_BMC_SDA")
		)
		(pad "7" smd rect
			(at 2.6924 1.5875 90)
			(size 0.4318 1.6764)
			(layers "B.Cu" "B.Mask" "B.Paste")
			(net "I3C_SPD_DDRABCD_CPU0_LVC1_R_SDA")
		)
		(pad "8" smd rect
			(at 2.6924 2.2225 90)
			(size 0.4318 1.6764)
			(layers "B.Cu" "B.Mask" "B.Paste")
			(net "GND")
		)
		(pad "9" smd rect
			(at -2.6924 2.2225 90)
			(size 0.4318 1.6764)
			(layers "B.Cu" "B.Mask" "B.Paste")
			(net "I3C_SPD_DDREFGH_CPU0_LVC1_R_SCL")
		)
		(pad "10" smd rect
			(at -2.6924 1.5875 90)
			(size 0.4318 1.6764)
			(layers "B.Cu" "B.Mask" "B.Paste")
			(net "I3C_SPD_DDREFGH_CPU0_BMC_SCL")
		)
		(pad "11" smd rect
			(at -2.6924 0.9525 90)
			(size 0.4318 1.6764)
			(layers "B.Cu" "B.Mask" "B.Paste")
			(net "I3C_SPD_DDREFGH_CPU0_R_SCL")
		)
		(pad "12" smd rect
			(at -2.6924 0.3175 90)
			(size 0.4318 1.6764)
			(layers "B.Cu" "B.Mask" "B.Paste")
			(net "I3C_SPD_DDREFGH_CPU0_LVC1_R_SDA")
		)
		(pad "13" smd rect
			(at -2.6924 -0.3175 90)
			(size 0.4318 1.6764)
			(layers "B.Cu" "B.Mask" "B.Paste")
			(net "I3C_SPD_DDREFGH_CPU0_BMC_SDA")
		)
		(pad "14" smd rect
			(at -2.6924 -0.9525 90)
			(size 0.4318 1.6764)
			(layers "B.Cu" "B.Mask" "B.Paste")
			(net "I3C_SPD_DDREFGH_CPU0_R_SDA")
		)
		(pad "15" smd rect
			(at -2.6924 -1.5875 90)
			(size 0.4318 1.6764)
			(layers "B.Cu" "B.Mask" "B.Paste")
			(net "PD_I3C_SPD_DDR_CPU0_OE_N")
		)
		(pad "16" smd rect
			(at -2.6924 -2.2225 90)
			(size 0.4318 1.6764)
			(layers "B.Cu" "B.Mask" "B.Paste")
			(net "P3V3_AUX")
		)
	)
)
